# SCM (Grand Teton) — schematic netlist excerpt (pin names and nets, part order shuffled) for the footprints in the layout excerpt that follows; sources: Cadence DE-HDL packaged netlist, KiCad conversion of 12092022_DA0F0TMDCD0_F0T_Management_Board_D_brd_V3_OCP.brd

R504  Q_RES  8.2K 5% CHIP  pkg 0402LF  page 50 : A = P3V3_AUX ; B = REAR_ID_RST_BTN_N
C252  Q_CAP  1UF 25V 10% EMPTY  pkg C0402  page 52 : A = PWRGD_P3V3_RGM_R ; B = GND

(kicad_pcb
	(version 20260206)
	(generator "pcbnew")
	(generator_version "10.0")
	(general
		(thickness 1.6)
		(legacy_teardrops no)
	)
	(paper "A4")
	(title_block
		(title "12092022_DA0F0TMDCD0_F0T_Management_Board_D_brd_V3_OCP.brd")
		(comment 1 "Grand Teton / footprints 473-474 of 1440")
	)
	(layers
		(0 "F.Cu" signal "TOP")
		(4 "In1.Cu" signal "GND")
		(6 "In2.Cu" signal "IN1")
		(8 "In3.Cu" signal "GND1")
		(10 "In4.Cu" signal "IN2")
		(12 "In5.Cu" signal "VCC")
		(14 "In6.Cu" signal "VCC1")
		(16 "In7.Cu" signal "IN3")
		(18 "In8.Cu" signal "GND2")
		(20 "In9.Cu" signal "IN4")
		(22 "In10.Cu" signal "GND3")
		(2 "B.Cu" signal "BOTTOM")
		(9 "F.Adhes" user "F.Adhesive")
		(11 "B.Adhes" user "B.Adhesive")
		(13 "F.Paste" user "Package Geometry/Pastemask Top")
		(15 "B.Paste" user "Package Geometry/Pastemask Bottom")
		(5 "F.SilkS" user "Ref Des/Silkscreen Top")
		(7 "B.SilkS" user "Ref Des/Silkscreen Bottom")
		(1 "F.Mask" user "Board Geometry/Soldermask Top")
		(3 "B.Mask" user "Board Geometry/Soldermask Bottom")
		(17 "Dwgs.User" user "User.Drawings")
		(19 "Cmts.User" user "User.Comments")
		(21 "Eco1.User" user "User.Eco1")
		(23 "Eco2.User" user "User.Eco2")
		(25 "Edge.Cuts" user "Board Geometry/Outline")
		(27 "Margin" user)
		(31 "F.CrtYd" user "Package Geometry/Place Bound Top")
		(29 "B.CrtYd" user "Package Geometry/Place Bound Bottom")
		(35 "F.Fab" user "Ref Des/Assembly Top")
		(33 "B.Fab" user "Ref Des/Assembly Bottom")
	)
	(footprint ""
		(layer "F.Cu")
		(at 70.4088 -29.845 -90)
		(property "Reference" "C252"
			(at 0 0 270)
			(layer "F.SilkS")
			(hide yes)
			(effects
				(font
					(size 1.27 1.27)
				)
			)
		)
		(property "Value" ""
			(at 0 0 270)
			(layer "F.Fab")
			(effects
				(font
					(size 1.27 1.27)
				)
			)
		)
		(duplicate_pad_numbers_are_jumpers no)
		(fp_line
			(start -0.7874 0.4064)
			(end -0.7874 -0.4064)
			(stroke
				(width 0.1524)
				(type default)
			)
			(layer "F.SilkS")
		)
		(fp_line
			(start 0.7874 0.4064)
			(end -0.7874 0.4064)
			(stroke
				(width 0.1524)
				(type default)
			)
			(layer "F.SilkS")
		)
		(fp_line
			(start -0.7874 -0.4064)
			(end 0.7874 -0.4064)
			(stroke
				(width 0.1524)
				(type default)
			)
			(layer "F.SilkS")
		)
		(fp_line
			(start 0.7874 -0.4064)
			(end 0.7874 0.4064)
			(stroke
				(width 0.1524)
				(type default)
			)
			(layer "F.SilkS")
		)
		(fp_line
			(start -0.67945 0.3048)
			(end -0.67945 -0.305054)
			(stroke
				(width 0.1)
				(type default)
			)
			(layer "F.Fab")
		)
		(fp_line
			(start -0.12065 0.3048)
			(end -0.67945 0.3048)
			(stroke
				(width 0.1)
				(type default)
			)
			(layer "F.Fab")
		)
		(fp_line
			(start 0.120396 0.3048)
			(end 0.120396 0.2794)
			(stroke
				(width 0.1)
				(type default)
			)
			(layer "F.Fab")
		)
		(fp_line
			(start 0.67945 0.3048)
			(end 0.120396 0.3048)
			(stroke
				(width 0.1)
				(type default)
			)
			(layer "F.Fab")
		)
		(fp_line
			(start -0.12065 0.2794)
			(end -0.12065 0.3048)
			(stroke
				(width 0.1)
				(type default)
			)
			(layer "F.Fab")
		)
		(fp_line
			(start 0.120396 0.2794)
			(end -0.12065 0.2794)
			(stroke
				(width 0.1)
				(type default)
			)
			(layer "F.Fab")
		)
		(fp_line
			(start -0.12065 -0.2794)
			(end 0.12065 -0.2794)
			(stroke
				(width 0.1)
				(type default)
			)
			(layer "F.Fab")
		)
		(fp_line
			(start 0.12065 -0.2794)
			(end 0.12065 -0.3048)
			(stroke
				(width 0.1)
				(type default)
			)
			(layer "F.Fab")
		)
		(fp_line
			(start 0.12065 -0.3048)
			(end 0.67945 -0.3048)
			(stroke
				(width 0.1)
				(type default)
			)
			(layer "F.Fab")
		)
		(fp_line
			(start 0.67945 -0.3048)
			(end 0.67945 0.3048)
			(stroke
				(width 0.1)
				(type default)
			)
			(layer "F.Fab")
		)
		(fp_line
			(start -0.67945 -0.305054)
			(end -0.12065 -0.305054)
			(stroke
				(width 0.1)
				(type default)
			)
			(layer "F.Fab")
		)
		(fp_line
			(start -0.12065 -0.305054)
			(end -0.12065 -0.2794)
			(stroke
				(width 0.1)
				(type default)
			)
			(layer "F.Fab")
		)
		(pad "1" smd circle
			(at -0.40005 0 270)
			(size 0 0)
			(layers "F.Cu" "F.Mask" "F.Paste")
			(net "PWRGD_P3V3_RGM_R")
		)
		(pad "2" smd circle
			(at 0.40005 0 270)
			(size 0 0)
			(layers "F.Cu" "F.Mask" "F.Paste")
			(net "GND")
		)
	)
	(footprint ""
		(layer "F.Cu")
		(at 85.2932 -17.78 180)
		(property "Reference" "R504"
			(at 0 0 180)
			(layer "F.SilkS")
			(hide yes)
			(effects
				(font
					(size 1.27 1.27)
				)
			)
		)
		(property "Value" ""
			(at 0 0 180)
			(layer "F.Fab")
			(effects
				(font
					(size 1.27 1.27)
				)
			)
		)
		(duplicate_pad_numbers_are_jumpers no)
		(fp_line
			(start 0.7874 0.4064)
			(end -0.7874 0.4064)
			(stroke
				(width 0.1524)
				(type default)
			)
			(layer "F.SilkS")
		)
		(fp_line
			(start 0.7874 -0.4064)
			(end 0.7874 0.4064)
			(stroke
				(width 0.1524)
				(type default)
			)
			(layer "F.SilkS")
		)
		(fp_line
			(start -0.7874 0.4064)
			(end -0.7874 -0.4064)
			(stroke
				(width 0.1524)
				(type default)
			)
			(layer "F.SilkS")
		)
		(fp_line
			(start -0.7874 -0.4064)
			(end 0.7874 -0.4064)
			(stroke
				(width 0.1524)
				(type default)
			)
			(layer "F.SilkS")
		)
		(fp_line
			(start 0.67945 0.3048)
			(end 0.120396 0.3048)
			(stroke
				(width 0.1)
				(type default)
			)
			(layer "F.Fab")
		)
		(fp_line
			(start 0.67945 -0.3048)
			(end 0.67945 0.3048)
			(stroke
				(width 0.1)
				(type default)
			)
			(layer "F.Fab")
		)
		(fp_line
			(start 0.12065 -0.2794)
			(end 0.12065 -0.3048)
			(stroke
				(width 0.1)
				(type default)
			)
			(layer "F.Fab")
		)
		(fp_line
			(start 0.12065 -0.3048)
			(end 0.67945 -0.3048)
			(stroke
				(width 0.1)
				(type default)
			)
			(layer "F.Fab")
		)
		(fp_line
			(start 0.120396 0.3048)
			(end 0.120396 0.2794)
			(stroke
				(width 0.1)
				(type default)
			)
			(layer "F.Fab")
		)
		(fp_line
			(start 0.120396 0.2794)
			(end -0.12065 0.2794)
			(stroke
				(width 0.1)
				(type default)
			)
			(layer "F.Fab")
		)
		(fp_line
			(start -0.12065 0.3048)
			(end -0.67945 0.3048)
			(stroke
				(width 0.1)
				(type default)
			)
			(layer "F.Fab")
		)
		(fp_line
			(start -0.12065 0.2794)
			(end -0.12065 0.3048)
			(stroke
				(width 0.1)
				(type default)
			)
			(layer "F.Fab")
		)
		(fp_line
			(start -0.12065 -0.2794)
			(end 0.12065 -0.2794)
			(stroke
				(width 0.1)
				(type default)
			)
			(layer "F.Fab")
		)
		(fp_line
			(start -0.12065 -0.305054)
			(end -0.12065 -0.2794)
			(stroke
				(width 0.1)
				(type default)
			)
			(layer "F.Fab")
		)
		(fp_line
			(start -0.67945 0.3048)
			(end -0.67945 -0.305054)
			(stroke
				(width 0.1)
				(type default)
			)
			(layer "F.Fab")
		)
		(fp_line
			(start -0.67945 -0.305054)
			(end -0.12065 -0.305054)
			(stroke
				(width 0.1)
				(type default)
			)
			(layer "F.Fab")
		)
		(pad "1" smd circle
			(at -0.40005 0 180)
			(size 0 0)
			(layers "F.Cu" "F.Mask" "F.Paste")
			(net "P3V3_AUX")
		)
		(pad "2" smd circle
			(at 0.40005 0 180)
			(size 0 0)
			(layers "F.Cu" "F.Mask" "F.Paste")
			(net "REAR_ID_RST_BTN_N")
		)
	)
)
